(kicad_pcb
	(version 20260206)
	(generator "pcbnew")
	(generator_version "10.0")
	(general
		(thickness 1.6)
		(legacy_teardrops no)
	)
	(paper "A4")
	(title_block
		(title "Bryce Canyon_IOM_M2_16342-2_OCP.brd")
		(comment 1 "Bryce Canyon / footprints 1123-1130 of 1146")
	)
	(layers
		(0 "F.Cu" signal "TOP")
		(4 "In1.Cu" signal "L2GND")
		(6 "In2.Cu" signal "L3")
		(8 "In3.Cu" signal "L4VCC")
		(10 "In4.Cu" signal "L5VCC")
		(12 "In5.Cu" signal "L6")
		(14 "In6.Cu" signal "L7GND")
		(2 "B.Cu" signal "BOTTOM")
		(9 "F.Adhes" user "F.Adhesive")
		(11 "B.Adhes" user "B.Adhesive")
		(13 "F.Paste" user "Package Geometry/Pastemask Top")
		(15 "B.Paste" user "Package Geometry/Pastemask Bottom")
		(5 "F.SilkS" user "Ref Des/Silkscreen Top")
		(7 "B.SilkS" user "Ref Des/Silkscreen Bottom")
		(1 "F.Mask" user "Board Geometry/Soldermask Top")
		(3 "B.Mask" user "Board Geometry/Soldermask Bottom")
		(17 "Dwgs.User" user "User.Drawings")
		(19 "Cmts.User" user "User.Comments")
		(21 "Eco1.User" user "User.Eco1")
		(23 "Eco2.User" user "User.Eco2")
		(25 "Edge.Cuts" user "Board Geometry/Outline")
		(27 "Margin" user)
		(31 "F.CrtYd" user "Package Geometry/Place Bound Top")
		(29 "B.CrtYd" user "Package Geometry/Place Bound Bottom")
		(35 "F.Fab" user "Ref Des/Assembly Top")
		(33 "B.Fab" user "Ref Des/Assembly Bottom")
	)
	(footprint ""
		(layer "B.Cu")
		(at 20.591272 -129.074164 180)
		(property "Reference" "R252"
			(at 0 0 0)
			(layer "B.SilkS")
			(hide yes)
			(effects
				(font
					(size 1.27 1.27)
				)
				(justify mirror)
			)
		)
		(property "Value" "120R2F-GP"
			(at -0.064008 -3.993896 180)
			(unlocked yes)
			(layer "B.Fab")
			(hide yes)
			(effects
				(font
					(size 1.016 1.016)
					(thickness 0.1524)
				)
				(justify mirror)
			)
		)
		(property "Device Type" "R402H16"
			(at -0.064008 -5.517896 180)
			(unlocked yes)
			(layer "B.Fab")
			(hide yes)
			(effects
				(font
					(size 1.016 1.016)
					(thickness 0.1524)
				)
				(justify mirror)
			)
		)
		(duplicate_pad_numbers_are_jumpers no)
		(fp_line
			(start 0.508 -0.9398)
			(end 0.508 0.9398)
			(stroke
				(width 0.1524)
				(type default)
			)
			(layer "B.SilkS")
		)
		(fp_line
			(start -0.508 -0.9398)
			(end 0.508 -0.9398)
			(stroke
				(width 0.1524)
				(type default)
			)
			(layer "B.SilkS")
		)
		(fp_rect
			(start 0.508 0.9398)
			(end -0.508 -0.9398)
			(stroke
				(width 0)
				(type default)
			)
			(fill no)
			(layer "B.CrtYd")
		)
		(fp_rect
			(start 0.508 0.9398)
			(end -0.508 -0.9398)
			(stroke
				(width 0)
				(type default)
			)
			(fill no)
			(layer "B.Fab")
		)
		(pad "1" smd custom
			(at 0 -0.4445)
			(size 0.1397 0.1397)
			(layers "B.Cu" "B.Mask" "B.Paste")
			(net "GND")
			(options
				(clearance outline)
				(anchor circle)
			)
			(primitives
				(gr_poly
					(pts
						(arc
							(start -0.1778 0.2794)
							(mid -0.249642 0.249642)
							(end -0.2794 0.1778)
						)
						(arc
							(start -0.2794 -0.1778)
							(mid -0.249642 -0.249642)
							(end -0.1778 -0.2794)
						)
						(arc
							(start 0.1778 -0.2794)
							(mid 0.249642 -0.249642)
							(end 0.2794 -0.1778)
						)
						(arc
							(start 0.2794 0.1778)
							(mid 0.249642 0.249642)
							(end 0.1778 0.2794)
						)
					)
					(width 0)
					(fill yes)
				)
			)
		)
		(pad "2" smd custom
			(at 0 0.4445)
			(size 0.1397 0.1397)
			(layers "B.Cu" "B.Mask" "B.Paste")
			(net "MEMA_9")
			(options
				(clearance outline)
				(anchor circle)
			)
			(primitives
				(gr_poly
					(pts
						(arc
							(start -0.1778 0.2794)
							(mid -0.249642 0.249642)
							(end -0.2794 0.1778)
						)
						(arc
							(start -0.2794 -0.1778)
							(mid -0.249642 -0.249642)
							(end -0.1778 -0.2794)
						)
						(arc
							(start 0.1778 -0.2794)
							(mid 0.249642 -0.249642)
							(end 0.2794 -0.1778)
						)
						(arc
							(start 0.2794 0.1778)
							(mid 0.249642 0.249642)
							(end 0.1778 0.2794)
						)
					)
					(width 0)
					(fill yes)
				)
			)
		)
	)
	(footprint ""
		(layer "B.Cu")
		(at 131.97586 -19.7358 90)
		(property "Reference" "R743"
			(at 0 0 90)
			(layer "B.SilkS")
			(hide yes)
			(effects
				(font
					(size 1.27 1.27)
				)
				(justify mirror)
			)
		)
		(property "Value" "100KR2F-L1-GP"
			(at -0.064008 -3.993896 90)
			(unlocked yes)
			(layer "B.Fab")
			(hide yes)
			(effects
				(font
					(size 1.016 1.016)
					(thickness 0.1524)
				)
				(justify mirror)
			)
		)
		(property "Device Type" "R402H16"
			(at -0.064008 -5.517896 90)
			(unlocked yes)
			(layer "B.Fab")
			(hide yes)
			(effects
				(font
					(size 1.016 1.016)
					(thickness 0.1524)
				)
				(justify mirror)
			)
		)
		(duplicate_pad_numbers_are_jumpers no)
		(fp_line
			(start 0.508 -0.9398)
			(end 0.508 0.9398)
			(stroke
				(width 0.1524)
				(type default)
			)
			(layer "B.SilkS")
		)
		(fp_line
			(start -0.508 -0.9398)
			(end 0.508 -0.9398)
			(stroke
				(width 0.1524)
				(type default)
			)
			(layer "B.SilkS")
		)
		(fp_rect
			(start 0.508 0.9398)
			(end -0.508 -0.9398)
			(stroke
				(width 0)
				(type default)
			)
			(fill no)
			(layer "B.CrtYd")
		)
		(fp_rect
			(start 0.508 0.9398)
			(end -0.508 -0.9398)
			(stroke
				(width 0)
				(type default)
			)
			(fill no)
			(layer "B.Fab")
		)
		(pad "1" smd custom
			(at 0 -0.4445 270)
			(size 0.1397 0.1397)
			(layers "B.Cu" "B.Mask" "B.Paste")
			(net "P12V_IOM")
			(options
				(clearance outline)
				(anchor circle)
			)
			(primitives
				(gr_poly
					(pts
						(arc
							(start -0.1778 0.2794)
							(mid -0.249642 0.249642)
							(end -0.2794 0.1778)
						)
						(arc
							(start -0.2794 -0.1778)
							(mid -0.249642 -0.249642)
							(end -0.1778 -0.2794)
						)
						(arc
							(start 0.1778 -0.2794)
							(mid 0.249642 -0.249642)
							(end 0.2794 -0.1778)
						)
						(arc
							(start 0.2794 0.1778)
							(mid 0.249642 0.249642)
							(end 0.1778 0.2794)
						)
					)
					(width 0)
					(fill yes)
				)
			)
		)
		(pad "2" smd custom
			(at 0 0.4445 270)
			(size 0.1397 0.1397)
			(layers "B.Cu" "B.Mask" "B.Paste")
			(net "IOM_ADM1278_EN")
			(options
				(clearance outline)
				(anchor circle)
			)
			(primitives
				(gr_poly
					(pts
						(arc
							(start -0.1778 0.2794)
							(mid -0.249642 0.249642)
							(end -0.2794 0.1778)
						)
						(arc
							(start -0.2794 -0.1778)
							(mid -0.249642 -0.249642)
							(end -0.1778 -0.2794)
						)
						(arc
							(start 0.1778 -0.2794)
							(mid 0.249642 -0.249642)
							(end 0.2794 -0.1778)
						)
						(arc
							(start 0.2794 0.1778)
							(mid 0.249642 0.249642)
							(end 0.1778 0.2794)
						)
					)
					(width 0)
					(fill yes)
				)
			)
		)
	)
	(footprint ""
		(layer "B.Cu")
		(at 63.8048 -145.0594 90)
		(property "Reference" "R202"
			(at 0 0 90)
			(layer "B.SilkS")
			(hide yes)
			(effects
				(font
					(size 1.27 1.27)
				)
				(justify mirror)
			)
		)
		(property "Value" "2K2R2F-GP"
			(at -0.064008 -3.993896 90)
			(unlocked yes)
			(layer "B.Fab")
			(hide yes)
			(effects
				(font
					(size 1.016 1.016)
					(thickness 0.1524)
				)
				(justify mirror)
			)
		)
		(property "Device Type" "R402H16"
			(at -0.064008 -5.517896 90)
			(unlocked yes)
			(layer "B.Fab")
			(hide yes)
			(effects
				(font
					(size 1.016 1.016)
					(thickness 0.1524)
				)
				(justify mirror)
			)
		)
		(duplicate_pad_numbers_are_jumpers no)
		(fp_line
			(start 0.508 -0.9398)
			(end 0.508 0.9398)
			(stroke
				(width 0.1524)
				(type default)
			)
			(layer "B.SilkS")
		)
		(fp_line
			(start -0.508 -0.9398)
			(end 0.508 -0.9398)
			(stroke
				(width 0.1524)
				(type default)
			)
			(layer "B.SilkS")
		)
		(fp_rect
			(start 0.508 0.9398)
			(end -0.508 -0.9398)
			(stroke
				(width 0)
				(type default)
			)
			(fill no)
			(layer "B.CrtYd")
		)
		(fp_rect
			(start 0.508 0.9398)
			(end -0.508 -0.9398)
			(stroke
				(width 0)
				(type default)
			)
			(fill no)
			(layer "B.Fab")
		)
		(pad "1" smd custom
			(at 0 -0.4445 270)
			(size 0.1397 0.1397)
			(layers "B.Cu" "B.Mask" "B.Paste")
			(net "I2C_MEZZ_FRU_SENSOR_SDA")
			(options
				(clearance outline)
				(anchor circle)
			)
			(primitives
				(gr_poly
					(pts
						(arc
							(start -0.1778 0.2794)
							(mid -0.249642 0.249642)
							(end -0.2794 0.1778)
						)
						(arc
							(start -0.2794 -0.1778)
							(mid -0.249642 -0.249642)
							(end -0.1778 -0.2794)
						)
						(arc
							(start 0.1778 -0.2794)
							(mid 0.249642 -0.249642)
							(end 0.2794 -0.1778)
						)
						(arc
							(start 0.2794 0.1778)
							(mid 0.249642 0.249642)
							(end 0.1778 0.2794)
						)
					)
					(width 0)
					(fill yes)
				)
			)
		)
		(pad "2" smd custom
			(at 0 0.4445 270)
			(size 0.1397 0.1397)
			(layers "B.Cu" "B.Mask" "B.Paste")
			(net "P3V3_STBY")
			(options
				(clearance outline)
				(anchor circle)
			)
			(primitives
				(gr_poly
					(pts
						(arc
							(start -0.1778 0.2794)
							(mid -0.249642 0.249642)
							(end -0.2794 0.1778)
						)
						(arc
							(start -0.2794 -0.1778)
							(mid -0.249642 -0.249642)
							(end -0.1778 -0.2794)
						)
						(arc
							(start 0.1778 -0.2794)
							(mid 0.249642 -0.249642)
							(end 0.2794 -0.1778)
						)
						(arc
							(start 0.2794 0.1778)
							(mid 0.249642 0.249642)
							(end 0.1778 0.2794)
						)
					)
					(width 0)
					(fill yes)
				)
			)
		)
	)
	(footprint ""
		(layer "B.Cu")
		(at 190.46825 -133.831584 180)
		(property "Reference" "C610"
			(at 0 0 0)
			(layer "B.SilkS")
			(hide yes)
			(effects
				(font
					(size 1.27 1.27)
				)
				(justify mirror)
			)
		)
		(property "Value" "SC10U6D3V5KX-4GP"
			(at 0.0762 -6.1214 180)
			(unlocked yes)
			(layer "B.Fab")
			(hide yes)
			(effects
				(font
					(size 1.016 1.016)
					(thickness 0.1524)
				)
				(justify mirror)
			)
		)
		(property "Device Type" "C805H58"
			(at 0.0762 -8.1534 180)
			(unlocked yes)
			(layer "B.Fab")
			(hide yes)
			(effects
				(font
					(size 1.016 1.016)
					(thickness 0.1524)
				)
				(justify mirror)
			)
		)
		(duplicate_pad_numbers_are_jumpers no)
		(fp_line
			(start -0.635 0)
			(end 0.635 0)
			(stroke
				(width 0.508)
				(type default)
			)
			(layer "B.SilkS")
		)
		(fp_rect
			(start 0.9652 1.778)
			(end -0.9652 -1.778)
			(stroke
				(width 0)
				(type default)
			)
			(fill no)
			(layer "B.CrtYd")
		)
		(fp_poly
			(pts
				(xy 0.9652 -1.778) (xy -0.9652 -1.778) (xy -0.9652 1.778) (xy 0.9652 1.778)
			)
			(stroke
				(width 0)
				(type default)
			)
			(fill no)
			(layer "B.Fab")
		)
		(pad "1" smd rect
			(at 0 -0.9652)
			(size 1.397 1.143)
			(layers "B.Cu" "B.Mask" "B.Paste")
			(net "P3V3_M2")
		)
		(pad "2" smd rect
			(at 0 0.9652)
			(size 1.397 1.143)
			(layers "B.Cu" "B.Mask" "B.Paste")
			(net "GND")
		)
	)
	(footprint ""
		(layer "B.Cu")
		(at 207.094836 -99.532948)
		(property "Reference" "C632"
			(at 0 0 0)
			(layer "B.SilkS")
			(hide yes)
			(effects
				(font
					(size 1.27 1.27)
				)
				(justify mirror)
			)
		)
		(property "Value" "SCD1U16V2KX-3GP"
			(at -1.1811 -2.7051 0)
			(unlocked yes)
			(layer "B.Fab")
			(hide yes)
			(effects
				(font
					(size 1.016 1.016)
					(thickness 0.1524)
				)
				(justify mirror)
			)
		)
		(property "Device Type" "C402H22"
			(at -1.181354 -4.2291 0)
			(unlocked yes)
			(layer "B.Fab")
			(hide yes)
			(effects
				(font
					(size 1.016 1.016)
					(thickness 0.1524)
				)
				(justify mirror)
			)
		)
		(duplicate_pad_numbers_are_jumpers no)
		(fp_rect
			(start 0.4318 0.9525)
			(end -0.4318 -0.9525)
			(stroke
				(width 0)
				(type default)
			)
			(fill no)
			(layer "B.CrtYd")
		)
		(fp_rect
			(start 0.4318 0.9525)
			(end -0.4318 -0.9525)
			(stroke
				(width 0)
				(type default)
			)
			(fill no)
			(layer "B.Fab")
		)
		(pad "1" smd custom
			(at 0 -0.4445 180)
			(size 0.1524 0.1524)
			(layers "B.Cu" "B.Mask" "B.Paste")
			(net "U82_VREF2")
			(options
				(clearance outline)
				(anchor circle)
			)
			(primitives
				(gr_poly
					(pts
						(arc
							(start 0.3048 0.2032)
							(mid 0.275042 0.275042)
							(end 0.2032 0.3048)
						)
						(arc
							(start -0.2032 0.3048)
							(mid -0.275042 0.275042)
							(end -0.3048 0.2032)
						)
						(arc
							(start -0.3048 -0.2032)
							(mid -0.275042 -0.275042)
							(end -0.2032 -0.3048)
						)
						(arc
							(start 0.2032 -0.3048)
							(mid 0.275042 -0.275042)
							(end 0.3048 -0.2032)
						)
					)
					(width 0)
					(fill yes)
				)
			)
		)
		(pad "2" smd custom
			(at 0 0.4445 180)
			(size 0.1524 0.1524)
			(layers "B.Cu" "B.Mask" "B.Paste")
			(net "GND")
			(options
				(clearance outline)
				(anchor circle)
			)
			(primitives
				(gr_poly
					(pts
						(arc
							(start 0.3048 0.2032)
							(mid 0.275042 0.275042)
							(end 0.2032 0.3048)
						)
						(arc
							(start -0.2032 0.3048)
							(mid -0.275042 0.275042)
							(end -0.3048 0.2032)
						)
						(arc
							(start -0.3048 -0.2032)
							(mid -0.275042 -0.275042)
							(end -0.2032 -0.3048)
						)
						(arc
							(start 0.2032 -0.3048)
							(mid 0.275042 -0.275042)
							(end 0.3048 -0.2032)
						)
					)
					(width 0)
					(fill yes)
				)
			)
		)
	)
	(footprint ""
		(layer "B.Cu")
		(at 31.9024 -128.1684 -90)
		(property "Reference" "C508"
			(at 0 0 90)
			(layer "B.SilkS")
			(hide yes)
			(effects
				(font
					(size 1.27 1.27)
				)
				(justify mirror)
			)
		)
		(property "Value" "SCD1U16V2KX-3GP"
			(at -1.1811 -2.7051 270)
			(unlocked yes)
			(layer "B.Fab")
			(hide yes)
			(effects
				(font
					(size 1.016 1.016)
					(thickness 0.1524)
				)
				(justify mirror)
			)
		)
		(property "Device Type" "C402H22"
			(at -1.1811 -4.2291 270)
			(unlocked yes)
			(layer "B.Fab")
			(hide yes)
			(effects
				(font
					(size 1.016 1.016)
					(thickness 0.1524)
				)
				(justify mirror)
			)
		)
		(duplicate_pad_numbers_are_jumpers no)
		(fp_rect
			(start 0.4318 0.9525)
			(end -0.4318 -0.9525)
			(stroke
				(width 0)
				(type default)
			)
			(fill no)
			(layer "B.CrtYd")
		)
		(fp_rect
			(start 0.4318 0.9525)
			(end -0.4318 -0.9525)
			(stroke
				(width 0)
				(type default)
			)
			(fill no)
			(layer "B.Fab")
		)
		(pad "1" smd custom
			(at 0 -0.4445 90)
			(size 0.1524 0.1524)
			(layers "B.Cu" "B.Mask" "B.Paste")
			(net "P3V3_STBY")
			(options
				(clearance outline)
				(anchor circle)
			)
			(primitives
				(gr_poly
					(pts
						(arc
							(start 0.3048 0.2032)
							(mid 0.275042 0.275042)
							(end 0.2032 0.3048)
						)
						(arc
							(start -0.2032 0.3048)
							(mid -0.275042 0.275042)
							(end -0.3048 0.2032)
						)
						(arc
							(start -0.3048 -0.2032)
							(mid -0.275042 -0.275042)
							(end -0.2032 -0.3048)
						)
						(arc
							(start 0.2032 -0.3048)
							(mid 0.275042 -0.275042)
							(end 0.3048 -0.2032)
						)
					)
					(width 0)
					(fill yes)
				)
			)
		)
		(pad "2" smd custom
			(at 0 0.4445 90)
			(size 0.1524 0.1524)
			(layers "B.Cu" "B.Mask" "B.Paste")
			(net "GND")
			(options
				(clearance outline)
				(anchor circle)
			)
			(primitives
				(gr_poly
					(pts
						(arc
							(start 0.3048 0.2032)
							(mid 0.275042 0.275042)
							(end 0.2032 0.3048)
						)
						(arc
							(start -0.2032 0.3048)
							(mid -0.275042 0.275042)
							(end -0.3048 0.2032)
						)
						(arc
							(start -0.3048 -0.2032)
							(mid -0.275042 -0.275042)
							(end -0.2032 -0.3048)
						)
						(arc
							(start 0.2032 -0.3048)
							(mid 0.275042 -0.275042)
							(end 0.3048 -0.2032)
						)
					)
					(width 0)
					(fill yes)
				)
			)
		)
	)
	(footprint ""
		(layer "B.Cu")
		(at 170.035728 -123.622308 -90)
		(property "Reference" "C618"
			(at 0 0 90)
			(layer "B.SilkS")
			(hide yes)
			(effects
				(font
					(size 1.27 1.27)
				)
				(justify mirror)
			)
		)
		(property "Value" "SCD1U16V2KX-3GP"
			(at -1.1811 -2.7051 270)
			(unlocked yes)
			(layer "B.Fab")
			(hide yes)
			(effects
				(font
					(size 1.016 1.016)
					(thickness 0.1524)
				)
				(justify mirror)
			)
		)
		(property "Device Type" "C402H22"
			(at -1.1811 -4.2291 270)
			(unlocked yes)
			(layer "B.Fab")
			(hide yes)
			(effects
				(font
					(size 1.016 1.016)
					(thickness 0.1524)
				)
				(justify mirror)
			)
		)
		(duplicate_pad_numbers_are_jumpers no)
		(fp_rect
			(start 0.4318 0.9525)
			(end -0.4318 -0.9525)
			(stroke
				(width 0)
				(type default)
			)
			(fill no)
			(layer "B.CrtYd")
		)
		(fp_rect
			(start 0.4318 0.9525)
			(end -0.4318 -0.9525)
			(stroke
				(width 0)
				(type default)
			)
			(fill no)
			(layer "B.Fab")
		)
		(pad "1" smd custom
			(at 0 -0.4445 90)
			(size 0.1524 0.1524)
			(layers "B.Cu" "B.Mask" "B.Paste")
			(net "P3V3_M2")
			(options
				(clearance outline)
				(anchor circle)
			)
			(primitives
				(gr_poly
					(pts
						(arc
							(start 0.3048 0.2032)
							(mid 0.275042 0.275042)
							(end 0.2032 0.3048)
						)
						(arc
							(start -0.2032 0.3048)
							(mid -0.275042 0.275042)
							(end -0.3048 0.2032)
						)
						(arc
							(start -0.3048 -0.2032)
							(mid -0.275042 -0.275042)
							(end -0.2032 -0.3048)
						)
						(arc
							(start 0.2032 -0.3048)
							(mid 0.275042 -0.275042)
							(end 0.3048 -0.2032)
						)
					)
					(width 0)
					(fill yes)
				)
			)
		)
		(pad "2" smd custom
			(at 0 0.4445 90)
			(size 0.1524 0.1524)
			(layers "B.Cu" "B.Mask" "B.Paste")
			(net "GND")
			(options
				(clearance outline)
				(anchor circle)
			)
			(primitives
				(gr_poly
					(pts
						(arc
							(start 0.3048 0.2032)
							(mid 0.275042 0.275042)
							(end 0.2032 0.3048)
						)
						(arc
							(start -0.2032 0.3048)
							(mid -0.275042 0.275042)
							(end -0.3048 0.2032)
						)
						(arc
							(start -0.3048 -0.2032)
							(mid -0.275042 -0.275042)
							(end -0.2032 -0.3048)
						)
						(arc
							(start 0.2032 -0.3048)
							(mid 0.275042 -0.275042)
							(end 0.3048 -0.2032)
						)
					)
					(width 0)
					(fill yes)
				)
			)
		)
	)
	(footprint ""
		(layer "B.Cu")
		(at 94.8436 -158.5722)
		(property "Reference" "R21"
			(at 0 0 0)
			(layer "B.SilkS")
			(hide yes)
			(effects
				(font
					(size 1.27 1.27)
				)
				(justify mirror)
			)
		)
		(property "Value" "4K7R2F-GP"
			(at -0.064008 -3.993896 0)
			(unlocked yes)
			(layer "B.Fab")
			(hide yes)
			(effects
				(font
					(size 1.016 1.016)
					(thickness 0.1524)
				)
				(justify mirror)
			)
		)
		(property "Device Type" "R402H16"
			(at -0.064008 -5.517896 0)
			(unlocked yes)
			(layer "B.Fab")
			(hide yes)
			(effects
				(font
					(size 1.016 1.016)
					(thickness 0.1524)
				)
				(justify mirror)
			)
		)
		(duplicate_pad_numbers_are_jumpers no)
		(fp_line
			(start -0.508 -0.9398)
			(end 0.508 -0.9398)
			(stroke
				(width 0.1524)
				(type default)
			)
			(layer "B.SilkS")
		)
		(fp_line
			(start 0.508 -0.9398)
			(end 0.508 0.9398)
			(stroke
				(width 0.1524)
				(type default)
			)
			(layer "B.SilkS")
		)
		(fp_rect
			(start 0.508 0.9398)
			(end -0.508 -0.9398)
			(stroke
				(width 0)
				(type default)
			)
			(fill no)
			(layer "B.CrtYd")
		)
		(fp_rect
			(start 0.508 0.9398)
			(end -0.508 -0.9398)
			(stroke
				(width 0)
				(type default)
			)
			(fill no)
			(layer "B.Fab")
		)
		(pad "1" smd custom
			(at 0 -0.4445 180)
			(size 0.1397 0.1397)
			(layers "B.Cu" "B.Mask" "B.Paste")
			(net "P3V3_STBY")
			(options
				(clearance outline)
				(anchor circle)
			)
			(primitives
				(gr_poly
					(pts
						(arc
							(start -0.1778 0.2794)
							(mid -0.249642 0.249642)
							(end -0.2794 0.1778)
						)
						(arc
							(start -0.2794 -0.1778)
							(mid -0.249642 -0.249642)
							(end -0.1778 -0.2794)
						)
						(arc
							(start 0.1778 -0.2794)
							(mid 0.249642 -0.249642)
							(end 0.2794 -0.1778)
						)
						(arc
							(start 0.2794 0.1778)
							(mid 0.249642 0.249642)
							(end 0.1778 0.2794)
						)
					)
					(width 0)
					(fill yes)
				)
			)
		)
		(pad "2" smd custom
			(at 0 0.4445 180)
			(size 0.1397 0.1397)
			(layers "B.Cu" "B.Mask" "B.Paste")
			(net "USB_RESET_N")
			(options
				(clearance outline)
				(anchor circle)
			)
			(primitives
				(gr_poly
					(pts
						(arc
							(start -0.1778 0.2794)
							(mid -0.249642 0.249642)
							(end -0.2794 0.1778)
						)
						(arc
							(start -0.2794 -0.1778)
							(mid -0.249642 -0.249642)
							(end -0.1778 -0.2794)
						)
						(arc
							(start 0.1778 -0.2794)
							(mid 0.249642 -0.249642)
							(end 0.2794 -0.1778)
						)
						(arc
							(start 0.2794 0.1778)
							(mid 0.249642 0.249642)
							(end 0.1778 0.2794)
						)
					)
					(width 0)
					(fill yes)
				)
			)
		)
	)
)
